G04*
G04 #@! TF.GenerationSoftware,Altium Limited,Altium Designer,23.6.0 (18)*
G04*
G04 Layer_Color=16711935*
%FSLAX44Y44*%
%MOMM*%
G71*
G04*
G04 #@! TF.SameCoordinates,B62FFF2A-40BB-47C2-B022-6C0D6E2DF31E*
G04*
G04*
G04 #@! TF.FilePolarity,Negative*
G04*
G01*
G75*
%ADD59C,0.5064*%
%ADD70R,0.4500X2.0500*%
%ADD71C,6.1000*%
D59*
X69468Y121045D02*
D03*
X40000Y114000D02*
D03*
X50000Y115000D02*
D03*
X39000Y147000D02*
D03*
X118000Y47000D02*
D03*
X200000Y78350D02*
D03*
X207794Y79007D02*
D03*
X203112Y61996D02*
D03*
X211343Y71000D02*
D03*
X212000Y61000D02*
D03*
X63000Y38000D02*
D03*
X193000Y37000D02*
D03*
X208000Y193000D02*
D03*
X205000Y239000D02*
D03*
X206000Y215000D02*
D03*
Y259000D02*
D03*
Y268000D02*
D03*
Y276000D02*
D03*
X213640Y410220D02*
D03*
X209830Y402600D02*
D03*
X213640Y394980D02*
D03*
X209830Y387360D02*
D03*
X206020Y410220D02*
D03*
X202210Y402600D02*
D03*
X206020Y394980D02*
D03*
X202210Y387360D02*
D03*
Y174000D02*
D03*
Y158760D02*
D03*
Y143520D02*
D03*
X198400Y410220D02*
D03*
X194590Y402600D02*
D03*
X198400Y394980D02*
D03*
X194590Y387360D02*
D03*
X190780Y410220D02*
D03*
X186970Y402600D02*
D03*
X190780Y394980D02*
D03*
X186970Y387360D02*
D03*
X183160Y410220D02*
D03*
X179350Y402600D02*
D03*
X183160Y394980D02*
D03*
X179350Y387360D02*
D03*
X175540Y410220D02*
D03*
X171730Y402600D02*
D03*
X175540Y394980D02*
D03*
X171730Y387360D02*
D03*
X167920Y410220D02*
D03*
X164110Y402600D02*
D03*
X167920Y394980D02*
D03*
X164110Y387360D02*
D03*
X160300Y410220D02*
D03*
X156490Y402600D02*
D03*
X160300Y394980D02*
D03*
X156490Y387360D02*
D03*
X152680Y410220D02*
D03*
X148870Y402600D02*
D03*
X152680Y394980D02*
D03*
X148870Y387360D02*
D03*
X145060Y410220D02*
D03*
X141250Y402600D02*
D03*
X145060Y394980D02*
D03*
X141250Y387360D02*
D03*
X137440Y394980D02*
D03*
X133630Y387360D02*
D03*
X126010D02*
D03*
X110770Y372120D02*
D03*
X106960Y379740D02*
D03*
X103150Y372120D02*
D03*
X106960Y364500D02*
D03*
X103150Y341640D02*
D03*
X95530Y387360D02*
D03*
X99340Y379740D02*
D03*
X95530Y372120D02*
D03*
X99340Y364500D02*
D03*
X95530Y341640D02*
D03*
Y311160D02*
D03*
Y295920D02*
D03*
Y280680D02*
D03*
X87910Y387360D02*
D03*
X91720Y379740D02*
D03*
X87910Y372120D02*
D03*
X91720Y364500D02*
D03*
X87910Y341640D02*
D03*
Y326400D02*
D03*
X91720Y303540D02*
D03*
Y288300D02*
D03*
X87910Y280680D02*
D03*
X91720Y273060D02*
D03*
X87910Y265440D02*
D03*
X80290Y402600D02*
D03*
X84100Y394980D02*
D03*
X80290Y387360D02*
D03*
X84100Y379740D02*
D03*
X80290Y372120D02*
D03*
X84100Y364500D02*
D03*
Y334020D02*
D03*
X80290Y326400D02*
D03*
Y280680D02*
D03*
X84100Y273060D02*
D03*
X80290Y265440D02*
D03*
X76480Y410220D02*
D03*
X72670Y402600D02*
D03*
X76480Y394980D02*
D03*
X72670Y387360D02*
D03*
X76480Y379740D02*
D03*
X72670Y372120D02*
D03*
X76480Y334020D02*
D03*
X72670Y326400D02*
D03*
X76480Y318780D02*
D03*
Y273060D02*
D03*
X72670Y265440D02*
D03*
X68860Y410220D02*
D03*
X65050Y402600D02*
D03*
X68860Y394980D02*
D03*
X65050Y387360D02*
D03*
X68860Y379740D02*
D03*
X65050Y372120D02*
D03*
X68860Y334020D02*
D03*
X65050Y326400D02*
D03*
X68860Y318780D02*
D03*
Y273060D02*
D03*
X65050Y265440D02*
D03*
X61240Y379740D02*
D03*
X57430Y372120D02*
D03*
X61240Y334020D02*
D03*
X57430Y326400D02*
D03*
Y280680D02*
D03*
X53620Y379740D02*
D03*
X49810Y372120D02*
D03*
Y280680D02*
D03*
X42190D02*
D03*
X46000Y273060D02*
D03*
X42190Y265440D02*
D03*
X38380Y410220D02*
D03*
X34570Y402600D02*
D03*
Y280680D02*
D03*
X38380Y273060D02*
D03*
X34570Y265440D02*
D03*
X30760Y410220D02*
D03*
X26950Y326400D02*
D03*
X30760Y318780D02*
D03*
X26950Y311160D02*
D03*
X30760Y303540D02*
D03*
X26950Y295920D02*
D03*
X30760Y288300D02*
D03*
X26950Y280680D02*
D03*
X30760Y273060D02*
D03*
X26950Y265440D02*
D03*
X19330Y372120D02*
D03*
X23140Y364500D02*
D03*
X19330Y356880D02*
D03*
X23140Y349260D02*
D03*
X19330Y341640D02*
D03*
X23140Y334020D02*
D03*
X19330Y326400D02*
D03*
X23140Y318780D02*
D03*
X19330Y311160D02*
D03*
X23140Y303540D02*
D03*
X19330Y295920D02*
D03*
X23140Y288300D02*
D03*
X19330Y280680D02*
D03*
X23140Y273060D02*
D03*
X19330Y265440D02*
D03*
Y250200D02*
D03*
Y234960D02*
D03*
Y219720D02*
D03*
Y204480D02*
D03*
Y189240D02*
D03*
Y174000D02*
D03*
Y158760D02*
D03*
Y143520D02*
D03*
Y128280D02*
D03*
Y113040D02*
D03*
Y97800D02*
D03*
Y82560D02*
D03*
Y67320D02*
D03*
X15520Y379740D02*
D03*
X11710Y372120D02*
D03*
X15520Y364500D02*
D03*
X11710Y356880D02*
D03*
X15520Y349260D02*
D03*
X11710Y341640D02*
D03*
X15520Y334020D02*
D03*
X11710Y326400D02*
D03*
X15520Y318780D02*
D03*
X11710Y311160D02*
D03*
X15520Y303540D02*
D03*
X11710Y295920D02*
D03*
X15520Y288300D02*
D03*
X11710Y280680D02*
D03*
X15520Y273060D02*
D03*
X11710Y265440D02*
D03*
X15520Y257820D02*
D03*
X11710Y250200D02*
D03*
X15520Y242580D02*
D03*
X11710Y234960D02*
D03*
X15520Y227340D02*
D03*
X11710Y219720D02*
D03*
X15520Y212100D02*
D03*
X11710Y204480D02*
D03*
X15520Y196860D02*
D03*
X11710Y189240D02*
D03*
X15520Y181620D02*
D03*
X11710Y174000D02*
D03*
X15520Y166380D02*
D03*
X11710Y158760D02*
D03*
X15520Y151140D02*
D03*
X11710Y143520D02*
D03*
X15520Y135900D02*
D03*
X11710Y128280D02*
D03*
X15520Y120660D02*
D03*
X11710Y113040D02*
D03*
X15520Y105420D02*
D03*
X11710Y97800D02*
D03*
X15520Y90180D02*
D03*
X11710Y82560D02*
D03*
X15520Y74940D02*
D03*
X11710Y67320D02*
D03*
X15520Y59700D02*
D03*
X32151Y339810D02*
D03*
X31576Y332800D02*
D03*
X35076Y326800D02*
D03*
X38651Y320417D02*
D03*
X43408Y314602D02*
D03*
X55998Y314097D02*
D03*
X54580Y320095D02*
D03*
X50238Y325800D02*
D03*
X47228Y332057D02*
D03*
X46887Y338234D02*
D03*
X46651Y344528D02*
D03*
X41962Y367714D02*
D03*
X39820Y373823D02*
D03*
X31485Y353188D02*
D03*
X30909Y359800D02*
D03*
X29145Y365800D02*
D03*
X33000Y393477D02*
D03*
X23000Y383750D02*
D03*
X24523Y377500D02*
D03*
X28054Y371915D02*
D03*
X31719Y347000D02*
D03*
X46267Y350969D02*
D03*
X43782Y379467D02*
D03*
X41000Y393477D02*
D03*
X9000Y395000D02*
D03*
Y408000D02*
D03*
X62000Y394000D02*
D03*
X73000Y38000D02*
D03*
X187096Y64000D02*
D03*
X181031D02*
D03*
X78000Y86000D02*
D03*
X132530Y319000D02*
D03*
X126466D02*
D03*
X112000Y77000D02*
D03*
X106000Y106000D02*
D03*
X117000Y121000D02*
D03*
X102000Y119000D02*
D03*
X125000Y136750D02*
D03*
X94000D02*
D03*
X38000Y84000D02*
D03*
X83000Y317000D02*
D03*
X159000Y322000D02*
D03*
X50000Y161000D02*
D03*
X190000Y354000D02*
D03*
X177000Y340000D02*
D03*
X181000Y375000D02*
D03*
X145000Y368000D02*
D03*
X135000D02*
D03*
X95000Y334000D02*
D03*
X79000Y360000D02*
D03*
X39010Y160198D02*
D03*
X64425Y314602D02*
D03*
X36000Y314802D02*
D03*
X199000Y90000D02*
D03*
Y101000D02*
D03*
X198000Y117000D02*
D03*
Y126000D02*
D03*
X188000Y136000D02*
D03*
Y148000D02*
D03*
Y160000D02*
D03*
X159000Y152000D02*
D03*
Y145500D02*
D03*
Y139375D02*
D03*
X176000Y44000D02*
D03*
X195873Y44688D02*
D03*
X196187Y51172D02*
D03*
X111000Y35000D02*
D03*
X204114Y40000D02*
D03*
X203458Y48255D02*
D03*
X211000Y40000D02*
D03*
Y47870D02*
D03*
X152000Y36000D02*
D03*
X137000D02*
D03*
X123000Y35000D02*
D03*
X93000Y34000D02*
D03*
X33000Y31000D02*
D03*
Y38000D02*
D03*
X32880Y45166D02*
D03*
X33000Y51645D02*
D03*
X15000Y50312D02*
D03*
X12791Y42000D02*
D03*
X6395Y41971D02*
D03*
X6826Y50312D02*
D03*
X80000Y49000D02*
D03*
X45000D02*
D03*
X56000Y45000D02*
D03*
D70*
X140060Y15250D02*
D03*
X135060D02*
D03*
X130060D02*
D03*
X125060D02*
D03*
X120060D02*
D03*
X115060D02*
D03*
X110060D02*
D03*
X155060D02*
D03*
X150060D02*
D03*
X80060D02*
D03*
X90060D02*
D03*
X85060D02*
D03*
X95060D02*
D03*
X75060D02*
D03*
X70060D02*
D03*
X65060D02*
D03*
X60060D02*
D03*
X55060D02*
D03*
X50060D02*
D03*
X45060D02*
D03*
X40060D02*
D03*
X35060D02*
D03*
X30060D02*
D03*
X25060D02*
D03*
X100060D02*
D03*
X105060D02*
D03*
X145060D02*
D03*
X185060D02*
D03*
X200060D02*
D03*
X195060D02*
D03*
X190060D02*
D03*
X180060D02*
D03*
X20060D02*
D03*
D71*
X110000Y420000D02*
D03*
M02*
